(kicad_pcb
	(version 20260206)
	(generator "pcbnew")
	(generator_version "10.0")
	(general
		(thickness 1.6)
		(legacy_teardrops no)
	)
	(paper "A4")
	(title_block
		(title "Wiwynn_Tioga_Pass_MB.brd")
		(comment 1 "Tioga Pass / footprints 3842-3849 of 4770")
	)
	(layers
		(0 "F.Cu" signal "TOP")
		(4 "In1.Cu" signal "L2GND")
		(6 "In2.Cu" signal "L3")
		(8 "In3.Cu" signal "L4GND")
		(10 "In4.Cu" signal "L5")
		(12 "In5.Cu" signal "L6GND")
		(14 "In6.Cu" signal "L7VCC")
		(16 "In7.Cu" signal "L8VCC")
		(18 "In8.Cu" signal "L9GND")
		(20 "In9.Cu" signal "L10")
		(22 "In10.Cu" signal "L11GND")
		(24 "In11.Cu" signal "L12")
		(26 "In12.Cu" signal "L13GND")
		(2 "B.Cu" signal "BOTTOM")
		(9 "F.Adhes" user "F.Adhesive")
		(11 "B.Adhes" user "B.Adhesive")
		(13 "F.Paste" user "Package Geometry/Pastemask Top")
		(15 "B.Paste" user "Package Geometry/Pastemask Bottom")
		(5 "F.SilkS" user "Ref Des/Silkscreen Top")
		(7 "B.SilkS" user "Ref Des/Silkscreen Bottom")
		(1 "F.Mask" user "Board Geometry/Soldermask Top")
		(3 "B.Mask" user "Board Geometry/Soldermask Bottom")
		(17 "Dwgs.User" user "User.Drawings")
		(19 "Cmts.User" user "User.Comments")
		(21 "Eco1.User" user "User.Eco1")
		(23 "Eco2.User" user "User.Eco2")
		(25 "Edge.Cuts" user "Board Geometry/Outline")
		(27 "Margin" user)
		(31 "F.CrtYd" user "Package Geometry/Place Bound Top")
		(29 "B.CrtYd" user "Package Geometry/Place Bound Bottom")
		(35 "F.Fab" user "Ref Des/Assembly Top")
		(33 "B.Fab" user "Ref Des/Assembly Bottom")
	)
	(footprint ""
		(layer "B.Cu")
		(at 446.8876 -61.8236 -90)
		(property "Reference" "R1W42"
			(at 0.8382 -0.67818 270)
			(unlocked yes)
			(layer "B.SilkS")
			(effects
				(font
					(size 0.4064 0.254)
					(thickness 0.1524)
				)
				(justify left mirror)
			)
		)
		(property "Value" ""
			(at 0 0 90)
			(layer "B.Fab")
			(effects
				(font
					(size 1.27 1.27)
				)
				(justify mirror)
			)
		)
		(duplicate_pad_numbers_are_jumpers no)
		(fp_poly
			(pts
				(xy 0.2794 -0.1016) (xy -0.2794 -0.1016) (xy -0.2794 0.9906) (xy 0.2794 0.9906)
			)
			(stroke
				(width 0)
				(type default)
			)
			(fill no)
			(layer "B.CrtYd")
		)
		(fp_line
			(start -0.2794 0.9906)
			(end -0.2794 -0.1016)
			(stroke
				(width 0.1)
				(type default)
			)
			(layer "B.Fab")
		)
		(fp_line
			(start 0.2794 0.9906)
			(end -0.2794 0.9906)
			(stroke
				(width 0.1)
				(type default)
			)
			(layer "B.Fab")
		)
		(fp_line
			(start -0.2794 -0.1016)
			(end 0.2794 -0.1016)
			(stroke
				(width 0.1)
				(type default)
			)
			(layer "B.Fab")
		)
		(fp_line
			(start 0.2794 -0.1016)
			(end 0.2794 0.9906)
			(stroke
				(width 0.1)
				(type default)
			)
			(layer "B.Fab")
		)
		(pad "1" smd rect
			(at 0 0 90)
			(size 0.508 0.508)
			(layers "B.Cu" "B.Mask" "B.Paste")
			(net "P3V3_STBY")
		)
		(pad "2" smd rect
			(at 0 0.889 90)
			(size 0.508 0.508)
			(layers "B.Cu" "B.Mask" "B.Paste")
			(net "FM_GBE0_LVC3_MOD_ABS")
		)
		(zone
			(layer "B.Cu")
			(hatch none 0.5)
			(connect_pads
				(clearance 0)
			)
			(min_thickness 0.25)
			(keepout
				(tracks not_allowed)
				(vias allowed)
				(pads allowed)
				(copperpour not_allowed)
				(footprints allowed)
			)
			(placement
				(enabled no)
				(sheetname "")
			)
			(fill
				(thermal_gap 0.5)
				(thermal_bridge_width 0.5)
				(island_removal_mode 0)
			)
			(polygon
				(pts
					(xy 446.2526 -61.5696) (xy 446.2526 -62.0776) (xy 446.6336 -62.0776) (xy 446.6336 -61.5696)
				)
			)
		)
		(zone
			(layer "B.Cu")
			(hatch none 0.5)
			(connect_pads
				(clearance 0)
			)
			(min_thickness 0.25)
			(keepout
				(tracks allowed)
				(vias not_allowed)
				(pads allowed)
				(copperpour not_allowed)
				(footprints allowed)
			)
			(placement
				(enabled no)
				(sheetname "")
			)
			(fill
				(thermal_gap 0.5)
				(thermal_bridge_width 0.5)
				(island_removal_mode 0)
			)
			(polygon
				(pts
					(xy 446.6336 -61.5696) (xy 446.6336 -62.0776) (xy 446.2526 -62.0776) (xy 446.2526 -61.5696)
				)
			)
		)
	)
	(footprint ""
		(layer "B.Cu")
		(at 396.875 -37.846 180)
		(property "Reference" "R2U2"
			(at 0 0 0)
			(layer "B.SilkS")
			(hide yes)
			(effects
				(font
					(size 1.27 1.27)
				)
				(justify mirror)
			)
		)
		(property "Value" ""
			(at 0 0 0)
			(layer "B.Fab")
			(effects
				(font
					(size 1.27 1.27)
				)
				(justify mirror)
			)
		)
		(duplicate_pad_numbers_are_jumpers no)
		(fp_poly
			(pts
				(xy 0.2794 -0.1016) (xy -0.2794 -0.1016) (xy -0.2794 0.9906) (xy 0.2794 0.9906)
			)
			(stroke
				(width 0)
				(type default)
			)
			(fill no)
			(layer "B.CrtYd")
		)
		(fp_line
			(start 0.2794 0.9906)
			(end -0.2794 0.9906)
			(stroke
				(width 0.1)
				(type default)
			)
			(layer "B.Fab")
		)
		(fp_line
			(start 0.2794 -0.1016)
			(end 0.2794 0.9906)
			(stroke
				(width 0.1)
				(type default)
			)
			(layer "B.Fab")
		)
		(fp_line
			(start -0.2794 0.9906)
			(end -0.2794 -0.1016)
			(stroke
				(width 0.1)
				(type default)
			)
			(layer "B.Fab")
		)
		(fp_line
			(start -0.2794 -0.1016)
			(end 0.2794 -0.1016)
			(stroke
				(width 0.1)
				(type default)
			)
			(layer "B.Fab")
		)
		(pad "1" smd rect
			(at 0 0)
			(size 0.508 0.508)
			(layers "B.Cu" "B.Mask" "B.Paste")
			(net "P3V3_STBY")
		)
		(pad "2" smd rect
			(at 0 0.889)
			(size 0.508 0.508)
			(layers "B.Cu" "B.Mask" "B.Paste")
			(net "RST_PCH_SYSRST_BTN_OUT_N")
		)
		(zone
			(layer "B.Cu")
			(hatch none 0.5)
			(connect_pads
				(clearance 0)
			)
			(min_thickness 0.25)
			(keepout
				(tracks not_allowed)
				(vias allowed)
				(pads allowed)
				(copperpour not_allowed)
				(footprints allowed)
			)
			(placement
				(enabled no)
				(sheetname "")
			)
			(fill
				(thermal_gap 0.5)
				(thermal_bridge_width 0.5)
				(island_removal_mode 0)
			)
			(polygon
				(pts
					(xy 396.621 -38.481) (xy 397.129 -38.481) (xy 397.129 -38.1) (xy 396.621 -38.1)
				)
			)
		)
		(zone
			(layer "B.Cu")
			(hatch none 0.5)
			(connect_pads
				(clearance 0)
			)
			(min_thickness 0.25)
			(keepout
				(tracks allowed)
				(vias not_allowed)
				(pads allowed)
				(copperpour not_allowed)
				(footprints allowed)
			)
			(placement
				(enabled no)
				(sheetname "")
			)
			(fill
				(thermal_gap 0.5)
				(thermal_bridge_width 0.5)
				(island_removal_mode 0)
			)
			(polygon
				(pts
					(xy 396.621 -38.1) (xy 397.129 -38.1) (xy 397.129 -38.481) (xy 396.621 -38.481)
				)
			)
		)
	)
	(footprint ""
		(layer "B.Cu")
		(at 106.350054 -77.82814)
		(property "Reference" "C8P14"
			(at 0 0 0)
			(layer "B.SilkS")
			(hide yes)
			(effects
				(font
					(size 1.27 1.27)
				)
				(justify mirror)
			)
		)
		(property "Value" ""
			(at 0 0 0)
			(layer "B.Fab")
			(effects
				(font
					(size 1.27 1.27)
				)
				(justify mirror)
			)
		)
		(duplicate_pad_numbers_are_jumpers no)
		(fp_poly
			(pts
				(xy 0.7239 -0.2159) (xy -0.7239 -0.2159) (xy -0.7239 1.9939) (xy 0.7239 1.9939)
			)
			(stroke
				(width 0)
				(type default)
			)
			(fill no)
			(layer "B.CrtYd")
		)
		(fp_line
			(start -0.7239 -0.2159)
			(end 0.7239 -0.2159)
			(stroke
				(width 0.1)
				(type default)
			)
			(layer "B.Fab")
		)
		(fp_line
			(start -0.7239 1.9939)
			(end -0.7239 -0.2159)
			(stroke
				(width 0.1)
				(type default)
			)
			(layer "B.Fab")
		)
		(fp_line
			(start 0.7239 -0.2159)
			(end 0.7239 1.9939)
			(stroke
				(width 0.1)
				(type default)
			)
			(layer "B.Fab")
		)
		(fp_line
			(start 0.7239 1.9939)
			(end -0.7239 1.9939)
			(stroke
				(width 0.1)
				(type default)
			)
			(layer "B.Fab")
		)
		(pad "1" smd rect
			(at 0 0 180)
			(size 1.27 1.016)
			(layers "B.Cu" "B.Mask" "B.Paste")
			(net "PVCCMCP_CPU1")
		)
		(pad "2" smd rect
			(at 0 1.778 180)
			(size 1.27 1.016)
			(layers "B.Cu" "B.Mask" "B.Paste")
			(net "GND")
		)
		(zone
			(layer "B.Cu")
			(hatch none 0.5)
			(connect_pads
				(clearance 0)
			)
			(min_thickness 0.25)
			(keepout
				(tracks not_allowed)
				(vias allowed)
				(pads allowed)
				(copperpour not_allowed)
				(footprints allowed)
			)
			(placement
				(enabled no)
				(sheetname "")
			)
			(fill
				(thermal_gap 0.5)
				(thermal_bridge_width 0.5)
				(island_removal_mode 0)
			)
			(polygon
				(pts
					(xy 106.985054 -77.32014) (xy 105.715054 -77.32014) (xy 105.715054 -76.55814) (xy 106.985054 -76.55814)
				)
			)
		)
	)
	(footprint ""
		(layer "B.Cu")
		(at 109.065568 3.81 90)
		(property "Reference" "C7U7"
			(at 0 0 90)
			(layer "B.SilkS")
			(hide yes)
			(effects
				(font
					(size 1.27 1.27)
				)
				(justify mirror)
			)
		)
		(property "Value" ""
			(at 0 0 90)
			(layer "B.Fab")
			(effects
				(font
					(size 1.27 1.27)
				)
				(justify mirror)
			)
		)
		(duplicate_pad_numbers_are_jumpers no)
		(fp_poly
			(pts
				(xy 0.7239 -0.2159) (xy -0.7239 -0.2159) (xy -0.7239 1.9939) (xy 0.7239 1.9939)
			)
			(stroke
				(width 0)
				(type default)
			)
			(fill no)
			(layer "B.CrtYd")
		)
		(fp_line
			(start 0.7239 -0.2159)
			(end 0.7239 1.9939)
			(stroke
				(width 0.1)
				(type default)
			)
			(layer "B.Fab")
		)
		(fp_line
			(start -0.7239 -0.2159)
			(end 0.7239 -0.2159)
			(stroke
				(width 0.1)
				(type default)
			)
			(layer "B.Fab")
		)
		(fp_line
			(start 0.7239 1.9939)
			(end -0.7239 1.9939)
			(stroke
				(width 0.1)
				(type default)
			)
			(layer "B.Fab")
		)
		(fp_line
			(start -0.7239 1.9939)
			(end -0.7239 -0.2159)
			(stroke
				(width 0.1)
				(type default)
			)
			(layer "B.Fab")
		)
		(pad "1" smd rect
			(at 0 0 270)
			(size 1.27 1.016)
			(layers "B.Cu" "B.Mask" "B.Paste")
			(net "PVDDQ_GHJ")
		)
		(pad "2" smd rect
			(at 0 1.778 270)
			(size 1.27 1.016)
			(layers "B.Cu" "B.Mask" "B.Paste")
			(net "GND")
		)
		(zone
			(layer "B.Cu")
			(hatch none 0.5)
			(connect_pads
				(clearance 0)
			)
			(min_thickness 0.25)
			(keepout
				(tracks not_allowed)
				(vias allowed)
				(pads allowed)
				(copperpour not_allowed)
				(footprints allowed)
			)
			(placement
				(enabled no)
				(sheetname "")
			)
			(fill
				(thermal_gap 0.5)
				(thermal_bridge_width 0.5)
				(island_removal_mode 0)
			)
			(polygon
				(pts
					(xy 109.573568 3.175) (xy 109.573568 4.445) (xy 110.335568 4.445) (xy 110.335568 3.175)
				)
			)
		)
	)
	(footprint ""
		(layer "B.Cu")
		(at 17.145 -92.583 -90)
		(property "Reference" "R6W3"
			(at 0 0 90)
			(layer "B.SilkS")
			(hide yes)
			(effects
				(font
					(size 1.27 1.27)
				)
				(justify mirror)
			)
		)
		(property "Value" "*"
			(at -0.064008 -4.108196 270)
			(unlocked yes)
			(layer "B.Fab")
			(hide yes)
			(effects
				(font
					(size 1.27 1.016)
					(thickness 0.1524)
				)
				(justify mirror)
			)
		)
		(property "Device Type" "232KR2F-2-GP_SMD-RG1-232KR2F-2A"
			(at -0.064008 -5.632196 270)
			(unlocked yes)
			(layer "B.Fab")
			(hide yes)
			(effects
				(font
					(size 1.27 1.016)
					(thickness 0.1524)
				)
				(justify mirror)
			)
		)
		(duplicate_pad_numbers_are_jumpers no)
		(fp_line
			(start -0.508 -0.9398)
			(end 0.508 -0.9398)
			(stroke
				(width 0.1524)
				(type default)
			)
			(layer "B.SilkS")
		)
		(fp_line
			(start 0.508 -0.9398)
			(end 0.508 0.9398)
			(stroke
				(width 0.1524)
				(type default)
			)
			(layer "B.SilkS")
		)
		(fp_rect
			(start 0.508 0.9398)
			(end -0.508 -0.9398)
			(stroke
				(width 0)
				(type default)
			)
			(fill no)
			(layer "B.CrtYd")
		)
		(fp_rect
			(start 0.508 0.9398)
			(end -0.508 -0.9398)
			(stroke
				(width 0)
				(type default)
			)
			(fill no)
			(layer "B.Fab")
		)
		(pad "1" smd custom
			(at 0 -0.4445 90)
			(size 0.1397 0.1397)
			(layers "B.Cu" "B.Mask" "B.Paste")
			(net "UV_HIGH_SET_N")
			(options
				(clearance outline)
				(anchor circle)
			)
			(primitives
				(gr_poly
					(pts
						(arc
							(start -0.1778 0.2794)
							(mid -0.249642 0.249642)
							(end -0.2794 0.1778)
						)
						(arc
							(start -0.2794 -0.1778)
							(mid -0.249642 -0.249642)
							(end -0.1778 -0.2794)
						)
						(arc
							(start 0.1778 -0.2794)
							(mid 0.249642 -0.249642)
							(end 0.2794 -0.1778)
						)
						(arc
							(start 0.2794 0.1778)
							(mid 0.249642 0.249642)
							(end 0.1778 0.2794)
						)
					)
					(width 0)
					(fill yes)
				)
			)
		)
		(pad "2" smd custom
			(at 0 0.4445 90)
			(size 0.1397 0.1397)
			(layers "B.Cu" "B.Mask" "B.Paste")
			(net "A_P12V_STBY_FP_TRIGGER")
			(options
				(clearance outline)
				(anchor circle)
			)
			(primitives
				(gr_poly
					(pts
						(arc
							(start -0.1778 0.2794)
							(mid -0.249642 0.249642)
							(end -0.2794 0.1778)
						)
						(arc
							(start -0.2794 -0.1778)
							(mid -0.249642 -0.249642)
							(end -0.1778 -0.2794)
						)
						(arc
							(start 0.1778 -0.2794)
							(mid 0.249642 -0.249642)
							(end 0.2794 -0.1778)
						)
						(arc
							(start 0.2794 0.1778)
							(mid 0.249642 0.249642)
							(end 0.1778 0.2794)
						)
					)
					(width 0)
					(fill yes)
				)
			)
		)
	)
	(footprint ""
		(layer "B.Cu")
		(at 115.824 -70.739 -90)
		(property "Reference" "R7P21"
			(at 0 0 90)
			(layer "B.SilkS")
			(hide yes)
			(effects
				(font
					(size 1.27 1.27)
				)
				(justify mirror)
			)
		)
		(property "Value" ""
			(at 0 0 90)
			(layer "B.Fab")
			(effects
				(font
					(size 1.27 1.27)
				)
				(justify mirror)
			)
		)
		(duplicate_pad_numbers_are_jumpers no)
		(fp_poly
			(pts
				(xy 0.2794 -0.1016) (xy -0.2794 -0.1016) (xy -0.2794 0.9906) (xy 0.2794 0.9906)
			)
			(stroke
				(width 0)
				(type default)
			)
			(fill no)
			(layer "B.CrtYd")
		)
		(fp_line
			(start -0.2794 0.9906)
			(end -0.2794 -0.1016)
			(stroke
				(width 0.1)
				(type default)
			)
			(layer "B.Fab")
		)
		(fp_line
			(start 0.2794 0.9906)
			(end -0.2794 0.9906)
			(stroke
				(width 0.1)
				(type default)
			)
			(layer "B.Fab")
		)
		(fp_line
			(start -0.2794 -0.1016)
			(end 0.2794 -0.1016)
			(stroke
				(width 0.1)
				(type default)
			)
			(layer "B.Fab")
		)
		(fp_line
			(start 0.2794 -0.1016)
			(end 0.2794 0.9906)
			(stroke
				(width 0.1)
				(type default)
			)
			(layer "B.Fab")
		)
		(pad "1" smd rect
			(at 0 0 90)
			(size 0.508 0.508)
			(layers "B.Cu" "B.Mask" "B.Paste")
			(net "H_CPU1_MEMKLM_MEMHOT_G_N")
		)
		(pad "2" smd rect
			(at 0 0.889 90)
			(size 0.508 0.508)
			(layers "B.Cu" "B.Mask" "B.Paste")
			(net "PVCCIO_CPU1")
		)
		(zone
			(layer "B.Cu")
			(hatch none 0.5)
			(connect_pads
				(clearance 0)
			)
			(min_thickness 0.25)
			(keepout
				(tracks not_allowed)
				(vias allowed)
				(pads allowed)
				(copperpour not_allowed)
				(footprints allowed)
			)
			(placement
				(enabled no)
				(sheetname "")
			)
			(fill
				(thermal_gap 0.5)
				(thermal_bridge_width 0.5)
				(island_removal_mode 0)
			)
			(polygon
				(pts
					(xy 115.189 -70.485) (xy 115.189 -70.993) (xy 115.57 -70.993) (xy 115.57 -70.485)
				)
			)
		)
		(zone
			(layer "B.Cu")
			(hatch none 0.5)
			(connect_pads
				(clearance 0)
			)
			(min_thickness 0.25)
			(keepout
				(tracks allowed)
				(vias not_allowed)
				(pads allowed)
				(copperpour not_allowed)
				(footprints allowed)
			)
			(placement
				(enabled no)
				(sheetname "")
			)
			(fill
				(thermal_gap 0.5)
				(thermal_bridge_width 0.5)
				(island_removal_mode 0)
			)
			(polygon
				(pts
					(xy 115.57 -70.485) (xy 115.57 -70.993) (xy 115.189 -70.993) (xy 115.189 -70.485)
				)
			)
		)
	)
	(footprint ""
		(layer "B.Cu")
		(at 494.702084 -46.184312)
		(property "Reference" "R25W136"
			(at 0.8382 -0.67818 0)
			(unlocked yes)
			(layer "B.SilkS")
			(effects
				(font
					(size 0.4064 0.254)
					(thickness 0.1524)
				)
				(justify left mirror)
			)
		)
		(property "Value" ""
			(at 0 0 0)
			(layer "B.Fab")
			(effects
				(font
					(size 1.27 1.27)
				)
				(justify mirror)
			)
		)
		(duplicate_pad_numbers_are_jumpers no)
		(fp_poly
			(pts
				(xy 0.2794 -0.1016) (xy -0.2794 -0.1016) (xy -0.2794 0.9906) (xy 0.2794 0.9906)
			)
			(stroke
				(width 0)
				(type default)
			)
			(fill no)
			(layer "B.CrtYd")
		)
		(fp_line
			(start -0.2794 -0.1016)
			(end 0.2794 -0.1016)
			(stroke
				(width 0.1)
				(type default)
			)
			(layer "B.Fab")
		)
		(fp_line
			(start -0.2794 0.9906)
			(end -0.2794 -0.1016)
			(stroke
				(width 0.1)
				(type default)
			)
			(layer "B.Fab")
		)
		(fp_line
			(start 0.2794 -0.1016)
			(end 0.2794 0.9906)
			(stroke
				(width 0.1)
				(type default)
			)
			(layer "B.Fab")
		)
		(fp_line
			(start 0.2794 0.9906)
			(end -0.2794 0.9906)
			(stroke
				(width 0.1)
				(type default)
			)
			(layer "B.Fab")
		)
		(pad "1" smd rect
			(at 0 0 180)
			(size 0.508 0.508)
			(layers "B.Cu" "B.Mask" "B.Paste")
			(net "I2C_BMC_VGA_DDC_SDA_G")
		)
		(pad "2" smd rect
			(at 0 0.889 180)
			(size 0.508 0.508)
			(layers "B.Cu" "B.Mask" "B.Paste")
			(net "V_IBMC_5V_DDC_SDA_J")
		)
		(zone
			(layer "B.Cu")
			(hatch none 0.5)
			(connect_pads
				(clearance 0)
			)
			(min_thickness 0.25)
			(keepout
				(tracks allowed)
				(vias not_allowed)
				(pads allowed)
				(copperpour not_allowed)
				(footprints allowed)
			)
			(placement
				(enabled no)
				(sheetname "")
			)
			(fill
				(thermal_gap 0.5)
				(thermal_bridge_width 0.5)
				(island_removal_mode 0)
			)
			(polygon
				(pts
					(xy 494.956084 -45.930312) (xy 494.448084 -45.930312) (xy 494.448084 -45.549312) (xy 494.956084 -45.549312)
				)
			)
		)
		(zone
			(layer "B.Cu")
			(hatch none 0.5)
			(connect_pads
				(clearance 0)
			)
			(min_thickness 0.25)
			(keepout
				(tracks not_allowed)
				(vias allowed)
				(pads allowed)
				(copperpour not_allowed)
				(footprints allowed)
			)
			(placement
				(enabled no)
				(sheetname "")
			)
			(fill
				(thermal_gap 0.5)
				(thermal_bridge_width 0.5)
				(island_removal_mode 0)
			)
			(polygon
				(pts
					(xy 494.956084 -45.549312) (xy 494.448084 -45.549312) (xy 494.448084 -45.930312) (xy 494.956084 -45.930312)
				)
			)
		)
	)
	(footprint ""
		(layer "B.Cu")
		(at 111.836454 -73.51014)
		(property "Reference" "C7P13"
			(at 0 0 0)
			(layer "B.SilkS")
			(hide yes)
			(effects
				(font
					(size 1.27 1.27)
				)
				(justify mirror)
			)
		)
		(property "Value" ""
			(at 0 0 0)
			(layer "B.Fab")
			(effects
				(font
					(size 1.27 1.27)
				)
				(justify mirror)
			)
		)
		(duplicate_pad_numbers_are_jumpers no)
		(fp_poly
			(pts
				(xy 0.7239 -0.2159) (xy -0.7239 -0.2159) (xy -0.7239 1.9939) (xy 0.7239 1.9939)
			)
			(stroke
				(width 0)
				(type default)
			)
			(fill no)
			(layer "B.CrtYd")
		)
		(fp_line
			(start -0.7239 -0.2159)
			(end 0.7239 -0.2159)
			(stroke
				(width 0.1)
				(type default)
			)
			(layer "B.Fab")
		)
		(fp_line
			(start -0.7239 1.9939)
			(end -0.7239 -0.2159)
			(stroke
				(width 0.1)
				(type default)
			)
			(layer "B.Fab")
		)
		(fp_line
			(start 0.7239 -0.2159)
			(end 0.7239 1.9939)
			(stroke
				(width 0.1)
				(type default)
			)
			(layer "B.Fab")
		)
		(fp_line
			(start 0.7239 1.9939)
			(end -0.7239 1.9939)
			(stroke
				(width 0.1)
				(type default)
			)
			(layer "B.Fab")
		)
		(pad "1" smd rect
			(at 0 0 180)
			(size 1.27 1.016)
			(layers "B.Cu" "B.Mask" "B.Paste")
			(net "PVCCMCP_CPU1")
		)
		(pad "2" smd rect
			(at 0 1.778 180)
			(size 1.27 1.016)
			(layers "B.Cu" "B.Mask" "B.Paste")
			(net "GND")
		)
		(zone
			(layer "B.Cu")
			(hatch none 0.5)
			(connect_pads
				(clearance 0)
			)
			(min_thickness 0.25)
			(keepout
				(tracks not_allowed)
				(vias allowed)
				(pads allowed)
				(copperpour not_allowed)
				(footprints allowed)
			)
			(placement
				(enabled no)
				(sheetname "")
			)
			(fill
				(thermal_gap 0.5)
				(thermal_bridge_width 0.5)
				(island_removal_mode 0)
			)
			(polygon
				(pts
					(xy 112.471454 -73.00214) (xy 111.201454 -73.00214) (xy 111.201454 -72.24014) (xy 112.471454 -72.24014)
				)
			)
		)
	)
)
